(kicad_pcb
	(version 20260206)
	(generator "pcbnew")
	(generator_version "10.0")
	(general
		(thickness 1.6)
		(legacy_teardrops no)
	)
	(paper "A4")
	(title_block
		(title "04192023_DAF0TMB3IC0_F0TG_MB_C_brd_V02_OCP.brd")
		(comment 1 "Grand Teton / footprint 2352 of 8354 (J1), pads 227-291 of 291")
	)
	(layers
		(0 "F.Cu" signal "TOP")
		(4 "In1.Cu" signal "GND")
		(6 "In2.Cu" signal "IN1")
		(8 "In3.Cu" signal "GND1")
		(10 "In4.Cu" signal "IN2")
		(12 "In5.Cu" signal "GND2")
		(14 "In6.Cu" signal "IN3")
		(16 "In7.Cu" signal "GND3")
		(18 "In8.Cu" signal "VCC")
		(20 "In9.Cu" signal "VCC1")
		(22 "In10.Cu" signal "GND4")
		(24 "In11.Cu" signal "IN4")
		(26 "In12.Cu" signal "GND5")
		(28 "In13.Cu" signal "IN5")
		(30 "In14.Cu" signal "GND6")
		(32 "In15.Cu" signal "IN6")
		(34 "In16.Cu" signal "GND7")
		(2 "B.Cu" signal "BOTTOM")
		(9 "F.Adhes" user "F.Adhesive")
		(11 "B.Adhes" user "B.Adhesive")
		(13 "F.Paste" user "Package Geometry/Pastemask Top")
		(15 "B.Paste" user "Package Geometry/Pastemask Bottom")
		(5 "F.SilkS" user "Ref Des/Silkscreen Top")
		(7 "B.SilkS" user "Ref Des/Silkscreen Bottom")
		(1 "F.Mask" user "Board Geometry/Soldermask Top")
		(3 "B.Mask" user "Board Geometry/Soldermask Bottom")
		(17 "Dwgs.User" user "User.Drawings")
		(19 "Cmts.User" user "User.Comments")
		(21 "Eco1.User" user "User.Eco1")
		(23 "Eco2.User" user "User.Eco2")
		(25 "Edge.Cuts" user "Board Geometry/Outline")
		(27 "Margin" user)
		(31 "F.CrtYd" user "Package Geometry/Place Bound Top")
		(29 "B.CrtYd" user "Package Geometry/Place Bound Bottom")
		(35 "F.Fab" user "Ref Des/Assembly Top")
		(33 "B.Fab" user "Ref Des/Assembly Bottom")
	)
	(footprint ""
		(layer "F.Cu")
		(at 305.31816 -255.560068 180)
		(property "Reference" "J1"
			(at -2.2098 -81.984088 0)
			(unlocked yes)
			(layer "F.SilkS")
			(effects
				(font
					(size 0.7874 0.5842)
					(thickness 0.1524)
				)
			)
		)
		(property "Value" ""
			(at 0 0 180)
			(layer "F.Fab")
			(effects
				(font
					(size 1.27 1.27)
				)
			)
		)
		(duplicate_pad_numbers_are_jumpers no)
		(pad "227" smd rect
			(at 2.050034 11.474958 90)
			(size 0.519938 1.4986)
			(layers "F.Cu" "F.Mask" "F.Paste")
			(net "M_A_CPU0_SB_PAR")
		)
		(pad "228" smd rect
			(at 2.050034 12.325096 90)
			(size 0.519938 1.4986)
			(layers "F.Cu" "F.Mask" "F.Paste")
			(net "GND")
		)
		(pad "229" smd rect
			(at 2.050034 13.17498 90)
			(size 0.519938 1.4986)
			(layers "F.Cu" "F.Mask" "F.Paste")
			(net "M_A_CPU0_SB_CS_N<1>")
		)
		(pad "230" smd rect
			(at 2.050034 14.025118 90)
			(size 0.519938 1.4986)
			(layers "F.Cu" "F.Mask" "F.Paste")
			(net "GND")
		)
		(pad "231" smd rect
			(at 2.050034 14.875002 90)
			(size 0.519938 1.4986)
			(layers "F.Cu" "F.Mask" "F.Paste")
			(net "Net_2254")
		)
		(pad "232" smd rect
			(at 2.050034 15.724886 90)
			(size 0.519938 1.4986)
			(layers "F.Cu" "F.Mask" "F.Paste")
			(net "Net_2255")
		)
		(pad "233" smd rect
			(at 2.050034 16.575024 90)
			(size 0.519938 1.4986)
			(layers "F.Cu" "F.Mask" "F.Paste")
			(net "GND")
		)
		(pad "234" smd rect
			(at 2.050034 17.424908 90)
			(size 0.519938 1.4986)
			(layers "F.Cu" "F.Mask" "F.Paste")
			(net "M_A_CPU0_SB_CB<6>")
		)
		(pad "235" smd rect
			(at 2.050034 18.275046 90)
			(size 0.519938 1.4986)
			(layers "F.Cu" "F.Mask" "F.Paste")
			(net "GND")
		)
		(pad "236" smd rect
			(at 2.050034 19.12493 90)
			(size 0.519938 1.4986)
			(layers "F.Cu" "F.Mask" "F.Paste")
			(net "M_A_CPU0_SB_CB<7>")
		)
		(pad "237" smd rect
			(at 2.050034 19.975068 90)
			(size 0.519938 1.4986)
			(layers "F.Cu" "F.Mask" "F.Paste")
			(net "GND")
		)
		(pad "238" smd rect
			(at 2.050034 20.824952 90)
			(size 0.519938 1.4986)
			(layers "F.Cu" "F.Mask" "F.Paste")
			(net "M_A_CPU0_SB_DQS_DN<4>")
		)
		(pad "239" smd rect
			(at 2.050034 21.67509 90)
			(size 0.519938 1.4986)
			(layers "F.Cu" "F.Mask" "F.Paste")
			(net "M_A_CPU0_SB_DQS_DP<4>")
		)
		(pad "240" smd rect
			(at 2.050034 22.524974 90)
			(size 0.519938 1.4986)
			(layers "F.Cu" "F.Mask" "F.Paste")
			(net "GND")
		)
		(pad "241" smd rect
			(at 2.050034 23.375112 90)
			(size 0.519938 1.4986)
			(layers "F.Cu" "F.Mask" "F.Paste")
			(net "M_A_CPU0_SB_CB<2>")
		)
		(pad "242" smd rect
			(at 2.050034 24.224996 90)
			(size 0.519938 1.4986)
			(layers "F.Cu" "F.Mask" "F.Paste")
			(net "GND")
		)
		(pad "243" smd rect
			(at 2.050034 25.07488 90)
			(size 0.519938 1.4986)
			(layers "F.Cu" "F.Mask" "F.Paste")
			(net "M_A_CPU0_SB_CB<3>")
		)
		(pad "244" smd rect
			(at 2.050034 25.925018 90)
			(size 0.519938 1.4986)
			(layers "F.Cu" "F.Mask" "F.Paste")
			(net "GND")
		)
		(pad "245" smd rect
			(at 2.050034 26.774902 90)
			(size 0.519938 1.4986)
			(layers "F.Cu" "F.Mask" "F.Paste")
			(net "M_A_CPU0_SB_DQ<2>")
		)
		(pad "246" smd rect
			(at 2.050034 27.62504 90)
			(size 0.519938 1.4986)
			(layers "F.Cu" "F.Mask" "F.Paste")
			(net "GND")
		)
		(pad "247" smd rect
			(at 2.050034 28.474924 90)
			(size 0.519938 1.4986)
			(layers "F.Cu" "F.Mask" "F.Paste")
			(net "M_A_CPU0_SB_DQ<3>")
		)
		(pad "248" smd rect
			(at 2.050034 29.325062 90)
			(size 0.519938 1.4986)
			(layers "F.Cu" "F.Mask" "F.Paste")
			(net "GND")
		)
		(pad "249" smd rect
			(at 2.050034 30.174946 90)
			(size 0.519938 1.4986)
			(layers "F.Cu" "F.Mask" "F.Paste")
			(net "M_A_CPU0_SB_DQS_DN<5>")
		)
		(pad "250" smd rect
			(at 2.050034 31.025084 90)
			(size 0.519938 1.4986)
			(layers "F.Cu" "F.Mask" "F.Paste")
			(net "M_A_CPU0_SB_DQS_DP<5>")
		)
		(pad "251" smd rect
			(at 2.050034 31.874968 90)
			(size 0.519938 1.4986)
			(layers "F.Cu" "F.Mask" "F.Paste")
			(net "GND")
		)
		(pad "252" smd rect
			(at 2.050034 32.725106 90)
			(size 0.519938 1.4986)
			(layers "F.Cu" "F.Mask" "F.Paste")
			(net "M_A_CPU0_SB_DQ<6>")
		)
		(pad "253" smd rect
			(at 2.050034 33.57499 90)
			(size 0.519938 1.4986)
			(layers "F.Cu" "F.Mask" "F.Paste")
			(net "GND")
		)
		(pad "254" smd rect
			(at 2.050034 34.425128 90)
			(size 0.519938 1.4986)
			(layers "F.Cu" "F.Mask" "F.Paste")
			(net "M_A_CPU0_SB_DQ<7>")
		)
		(pad "255" smd rect
			(at 2.050034 35.275012 90)
			(size 0.519938 1.4986)
			(layers "F.Cu" "F.Mask" "F.Paste")
			(net "GND")
		)
		(pad "256" smd rect
			(at 2.050034 36.124896 90)
			(size 0.519938 1.4986)
			(layers "F.Cu" "F.Mask" "F.Paste")
			(net "M_A_CPU0_SB_DQ<10>")
		)
		(pad "257" smd rect
			(at 2.050034 36.975034 90)
			(size 0.519938 1.4986)
			(layers "F.Cu" "F.Mask" "F.Paste")
			(net "GND")
		)
		(pad "258" smd rect
			(at 2.050034 37.824918 90)
			(size 0.519938 1.4986)
			(layers "F.Cu" "F.Mask" "F.Paste")
			(net "M_A_CPU0_SB_DQ<11>")
		)
		(pad "259" smd rect
			(at 2.050034 38.675056 90)
			(size 0.519938 1.4986)
			(layers "F.Cu" "F.Mask" "F.Paste")
			(net "GND")
		)
		(pad "260" smd rect
			(at 2.050034 39.52494 90)
			(size 0.519938 1.4986)
			(layers "F.Cu" "F.Mask" "F.Paste")
			(net "M_A_CPU0_SB_DQS_DN<6>")
		)
		(pad "261" smd rect
			(at 2.050034 40.375078 90)
			(size 0.519938 1.4986)
			(layers "F.Cu" "F.Mask" "F.Paste")
			(net "M_A_CPU0_SB_DQS_DP<6>")
		)
		(pad "262" smd rect
			(at 2.050034 41.224962 90)
			(size 0.519938 1.4986)
			(layers "F.Cu" "F.Mask" "F.Paste")
			(net "GND")
		)
		(pad "263" smd rect
			(at 2.050034 42.0751 90)
			(size 0.519938 1.4986)
			(layers "F.Cu" "F.Mask" "F.Paste")
			(net "M_A_CPU0_SB_DQ<14>")
		)
		(pad "264" smd rect
			(at 2.050034 42.924984 90)
			(size 0.519938 1.4986)
			(layers "F.Cu" "F.Mask" "F.Paste")
			(net "GND")
		)
		(pad "265" smd rect
			(at 2.050034 43.775122 90)
			(size 0.519938 1.4986)
			(layers "F.Cu" "F.Mask" "F.Paste")
			(net "M_A_CPU0_SB_DQ<15>")
		)
		(pad "266" smd rect
			(at 2.050034 44.625006 90)
			(size 0.519938 1.4986)
			(layers "F.Cu" "F.Mask" "F.Paste")
			(net "GND")
		)
		(pad "267" smd rect
			(at 2.050034 45.47489 90)
			(size 0.519938 1.4986)
			(layers "F.Cu" "F.Mask" "F.Paste")
			(net "M_A_CPU0_SB_DQ<18>")
		)
		(pad "268" smd rect
			(at 2.050034 46.325028 90)
			(size 0.519938 1.4986)
			(layers "F.Cu" "F.Mask" "F.Paste")
			(net "GND")
		)
		(pad "269" smd rect
			(at 2.050034 47.174912 90)
			(size 0.519938 1.4986)
			(layers "F.Cu" "F.Mask" "F.Paste")
			(net "M_A_CPU0_SB_DQ<19>")
		)
		(pad "270" smd rect
			(at 2.050034 48.02505 90)
			(size 0.519938 1.4986)
			(layers "F.Cu" "F.Mask" "F.Paste")
			(net "GND")
		)
		(pad "271" smd rect
			(at 2.050034 48.874934 90)
			(size 0.519938 1.4986)
			(layers "F.Cu" "F.Mask" "F.Paste")
			(net "M_A_CPU0_SB_DQS_DN<7>")
		)
		(pad "272" smd rect
			(at 2.050034 49.725072 90)
			(size 0.519938 1.4986)
			(layers "F.Cu" "F.Mask" "F.Paste")
			(net "M_A_CPU0_SB_DQS_DP<7>")
		)
		(pad "273" smd rect
			(at 2.050034 50.574956 90)
			(size 0.519938 1.4986)
			(layers "F.Cu" "F.Mask" "F.Paste")
			(net "GND")
		)
		(pad "274" smd rect
			(at 2.050034 51.425094 90)
			(size 0.519938 1.4986)
			(layers "F.Cu" "F.Mask" "F.Paste")
			(net "M_A_CPU0_SB_DQ<22>")
		)
		(pad "275" smd rect
			(at 2.050034 52.274978 90)
			(size 0.519938 1.4986)
			(layers "F.Cu" "F.Mask" "F.Paste")
			(net "GND")
		)
		(pad "276" smd rect
			(at 2.050034 53.125116 90)
			(size 0.519938 1.4986)
			(layers "F.Cu" "F.Mask" "F.Paste")
			(net "M_A_CPU0_SB_DQ<23>")
		)
		(pad "277" smd rect
			(at 2.050034 53.975 90)
			(size 0.519938 1.4986)
			(layers "F.Cu" "F.Mask" "F.Paste")
			(net "GND")
		)
		(pad "278" smd rect
			(at 2.050034 54.824884 90)
			(size 0.519938 1.4986)
			(layers "F.Cu" "F.Mask" "F.Paste")
			(net "M_A_CPU0_SB_DQ<26>")
		)
		(pad "279" smd rect
			(at 2.050034 55.675022 90)
			(size 0.519938 1.4986)
			(layers "F.Cu" "F.Mask" "F.Paste")
			(net "GND")
		)
		(pad "280" smd rect
			(at 2.050034 56.524906 90)
			(size 0.519938 1.4986)
			(layers "F.Cu" "F.Mask" "F.Paste")
			(net "M_A_CPU0_SB_DQ<27>")
		)
		(pad "281" smd rect
			(at 2.050034 57.375044 90)
			(size 0.519938 1.4986)
			(layers "F.Cu" "F.Mask" "F.Paste")
			(net "GND")
		)
		(pad "282" smd rect
			(at 2.050034 58.224928 90)
			(size 0.519938 1.4986)
			(layers "F.Cu" "F.Mask" "F.Paste")
			(net "M_A_CPU0_SB_DQS_DN<8>")
		)
		(pad "283" smd rect
			(at 2.050034 59.075066 90)
			(size 0.519938 1.4986)
			(layers "F.Cu" "F.Mask" "F.Paste")
			(net "M_A_CPU0_SB_DQS_DP<8>")
		)
		(pad "284" smd rect
			(at 2.050034 59.92495 90)
			(size 0.519938 1.4986)
			(layers "F.Cu" "F.Mask" "F.Paste")
			(net "GND")
		)
		(pad "285" smd rect
			(at 2.050034 60.775088 90)
			(size 0.519938 1.4986)
			(layers "F.Cu" "F.Mask" "F.Paste")
			(net "M_A_CPU0_SB_DQ<30>")
		)
		(pad "286" smd rect
			(at 2.050034 61.624972 90)
			(size 0.519938 1.4986)
			(layers "F.Cu" "F.Mask" "F.Paste")
			(net "GND")
		)
		(pad "287" smd rect
			(at 2.050034 62.47511 90)
			(size 0.519938 1.4986)
			(layers "F.Cu" "F.Mask" "F.Paste")
			(net "M_A_CPU0_SB_DQ<31>")
		)
		(pad "288" smd rect
			(at 2.050034 63.324994 90)
			(size 0.519938 1.4986)
			(layers "F.Cu" "F.Mask" "F.Paste")
			(net "GND")
		)
		(pad "G1" thru_hole oval
			(at 0 -68.97497 90)
			(size 1.7272 3.4798)
			(drill oval 1.2192 2.4638)
			(layers "*.Cu" "*.Mask")
			(remove_unused_layers no)
			(net "GND")
			(clearance 0.127)
			(thermal_gap 0.127)
		)
		(pad "G2" thru_hole oval
			(at 0 3.875024 90)
			(size 1.7272 3.4798)
			(drill oval 1.2192 2.4638)
			(layers "*.Cu" "*.Mask")
			(remove_unused_layers no)
			(net "GND")
			(clearance 0.127)
			(thermal_gap 0.127)
		)
		(pad "G3" thru_hole oval
			(at 0 68.97497 90)
			(size 1.7272 3.4798)
			(drill oval 1.2192 2.4638)
			(layers "*.Cu" "*.Mask")
			(remove_unused_layers no)
			(net "GND")
			(clearance 0.127)
			(thermal_gap 0.127)
		)
	)
)
